(kicad_pcb
	(version 20260206)
	(generator "pcbnew")
	(generator_version "10.0")
	(general
		(thickness 1.6)
		(legacy_teardrops no)
	)
	(paper "A4")
	(title_block
		(title "Bryce Canyon_SCC_16316-1_OCP.brd")
		(comment 1 "Bryce Canyon / footprints 562-569 of 1561")
	)
	(layers
		(0 "F.Cu" signal "TOP")
		(4 "In1.Cu" signal "L2GND")
		(6 "In2.Cu" signal "L3")
		(8 "In3.Cu" signal "L4VCC")
		(10 "In4.Cu" signal "L5VCC")
		(12 "In5.Cu" signal "L6")
		(14 "In6.Cu" signal "L7GND")
		(2 "B.Cu" signal "BOTTOM")
		(9 "F.Adhes" user "F.Adhesive")
		(11 "B.Adhes" user "B.Adhesive")
		(13 "F.Paste" user "Package Geometry/Pastemask Top")
		(15 "B.Paste" user "Package Geometry/Pastemask Bottom")
		(5 "F.SilkS" user "Ref Des/Silkscreen Top")
		(7 "B.SilkS" user "Ref Des/Silkscreen Bottom")
		(1 "F.Mask" user "Board Geometry/Soldermask Top")
		(3 "B.Mask" user "Board Geometry/Soldermask Bottom")
		(17 "Dwgs.User" user "User.Drawings")
		(19 "Cmts.User" user "User.Comments")
		(21 "Eco1.User" user "User.Eco1")
		(23 "Eco2.User" user "User.Eco2")
		(25 "Edge.Cuts" user "Board Geometry/Outline")
		(27 "Margin" user)
		(31 "F.CrtYd" user "Package Geometry/Place Bound Top")
		(29 "B.CrtYd" user "Package Geometry/Place Bound Bottom")
		(35 "F.Fab" user "Ref Des/Assembly Top")
		(33 "B.Fab" user "Ref Des/Assembly Bottom")
	)
	(footprint ""
		(layer "F.Cu")
		(at 149.4282 -124.5616 -90)
		(property "Reference" "C676"
			(at 0 0 270)
			(layer "F.SilkS")
			(hide yes)
			(effects
				(font
					(size 1.27 1.27)
				)
			)
		)
		(property "Value" "SC68P50V2JN-2-GP"
			(at 1.1811 -2.7051 270)
			(unlocked yes)
			(layer "F.Fab")
			(hide yes)
			(effects
				(font
					(size 1.016 1.016)
					(thickness 0.1524)
				)
			)
		)
		(property "Device Type" "C402H22"
			(at 1.1811 -4.2291 270)
			(unlocked yes)
			(layer "F.Fab")
			(hide yes)
			(effects
				(font
					(size 1.016 1.016)
					(thickness 0.1524)
				)
			)
		)
		(duplicate_pad_numbers_are_jumpers no)
		(fp_rect
			(start -0.4318 0.9525)
			(end 0.4318 -0.9525)
			(stroke
				(width 0)
				(type default)
			)
			(fill no)
			(layer "F.CrtYd")
		)
		(fp_rect
			(start -0.4318 0.9525)
			(end 0.4318 -0.9525)
			(stroke
				(width 0)
				(type default)
			)
			(fill no)
			(layer "F.Fab")
		)
		(pad "1" smd custom
			(at 0 -0.4445 270)
			(size 0.1524 0.1524)
			(layers "F.Cu" "F.Mask" "F.Paste")
			(net "P1V5_E_VFB")
			(options
				(clearance outline)
				(anchor circle)
			)
			(primitives
				(gr_poly
					(pts
						(arc
							(start 0.3048 -0.2032)
							(mid 0.275042 -0.275042)
							(end 0.2032 -0.3048)
						)
						(arc
							(start -0.2032 -0.3048)
							(mid -0.275042 -0.275042)
							(end -0.3048 -0.2032)
						)
						(arc
							(start -0.3048 0.2032)
							(mid -0.275042 0.275042)
							(end -0.2032 0.3048)
						)
						(arc
							(start 0.2032 0.3048)
							(mid 0.275042 0.275042)
							(end 0.3048 0.2032)
						)
					)
					(width 0)
					(fill yes)
				)
			)
		)
		(pad "2" smd custom
			(at 0 0.4445 270)
			(size 0.1524 0.1524)
			(layers "F.Cu" "F.Mask" "F.Paste")
			(net "P1V5_E_VFB_R")
			(options
				(clearance outline)
				(anchor circle)
			)
			(primitives
				(gr_poly
					(pts
						(arc
							(start 0.3048 -0.2032)
							(mid 0.275042 -0.275042)
							(end 0.2032 -0.3048)
						)
						(arc
							(start -0.2032 -0.3048)
							(mid -0.275042 -0.275042)
							(end -0.3048 -0.2032)
						)
						(arc
							(start -0.3048 0.2032)
							(mid -0.275042 0.275042)
							(end -0.2032 0.3048)
						)
						(arc
							(start 0.2032 0.3048)
							(mid 0.275042 0.275042)
							(end 0.3048 0.2032)
						)
					)
					(width 0)
					(fill yes)
				)
			)
		)
	)
	(footprint ""
		(layer "F.Cu")
		(at 43.1292 -37.338)
		(property "Reference" "R440"
			(at 0 0 0)
			(layer "F.SilkS")
			(hide yes)
			(effects
				(font
					(size 1.27 1.27)
				)
			)
		)
		(property "Value" "2D2R3-1-U-GP"
			(at -0.0254 -2.5146 0)
			(unlocked yes)
			(layer "F.Fab")
			(hide yes)
			(effects
				(font
					(size 1.016 1.016)
					(thickness 0.1524)
				)
			)
		)
		(property "Device Type" "R603H22"
			(at -0.0254 -4.0386 0)
			(unlocked yes)
			(layer "F.Fab")
			(hide yes)
			(effects
				(font
					(size 1.016 1.016)
					(thickness 0.1524)
				)
			)
		)
		(duplicate_pad_numbers_are_jumpers no)
		(fp_line
			(start -0.4826 0)
			(end -0.2032 0)
			(stroke
				(width 0.2032)
				(type default)
			)
			(layer "F.SilkS")
		)
		(fp_line
			(start 0.2032 0)
			(end 0.4826 0)
			(stroke
				(width 0.2032)
				(type default)
			)
			(layer "F.SilkS")
		)
		(fp_rect
			(start -0.5842 1.3335)
			(end 0.5842 -1.3335)
			(stroke
				(width 0)
				(type default)
			)
			(fill no)
			(layer "F.CrtYd")
		)
		(fp_rect
			(start -0.5842 1.3335)
			(end 0.5842 -1.3335)
			(stroke
				(width 0)
				(type default)
			)
			(fill no)
			(layer "F.Fab")
		)
		(pad "1" smd custom
			(at 0 -0.762)
			(size 0.2159 0.2159)
			(layers "F.Cu" "F.Mask" "F.Paste")
			(net "P0V9_BST_R")
			(options
				(clearance outline)
				(anchor circle)
			)
			(primitives
				(gr_poly
					(pts
						(arc
							(start -0.3302 -0.4318)
							(mid -0.402042 -0.402042)
							(end -0.4318 -0.3302)
						)
						(arc
							(start -0.4318 0.3302)
							(mid -0.402042 0.402042)
							(end -0.3302 0.4318)
						)
						(arc
							(start 0.3302 0.4318)
							(mid 0.402042 0.402042)
							(end 0.4318 0.3302)
						)
						(arc
							(start 0.4318 -0.3302)
							(mid 0.402042 -0.402042)
							(end 0.3302 -0.4318)
						)
					)
					(width 0)
					(fill yes)
				)
			)
		)
		(pad "2" smd custom
			(at 0 0.762)
			(size 0.2159 0.2159)
			(layers "F.Cu" "F.Mask" "F.Paste")
			(net "P0V9_SW")
			(options
				(clearance outline)
				(anchor circle)
			)
			(primitives
				(gr_poly
					(pts
						(arc
							(start -0.3302 -0.4318)
							(mid -0.402042 -0.402042)
							(end -0.4318 -0.3302)
						)
						(arc
							(start -0.4318 0.3302)
							(mid -0.402042 0.402042)
							(end -0.3302 0.4318)
						)
						(arc
							(start 0.3302 0.4318)
							(mid 0.402042 0.402042)
							(end 0.4318 0.3302)
						)
						(arc
							(start 0.4318 -0.3302)
							(mid 0.402042 -0.402042)
							(end 0.3302 -0.4318)
						)
					)
					(width 0)
					(fill yes)
				)
			)
		)
	)
	(footprint ""
		(layer "F.Cu")
		(at 170.8912 -113.1316)
		(property "Reference" "C603"
			(at 0 0 0)
			(layer "F.SilkS")
			(hide yes)
			(effects
				(font
					(size 1.27 1.27)
				)
			)
		)
		(property "Value" "SC1U16V3KX-5GP"
			(at 0 -2.8194 0)
			(unlocked yes)
			(layer "F.Fab")
			(hide yes)
			(effects
				(font
					(size 1.016 1.016)
					(thickness 0.1524)
				)
			)
		)
		(property "Device Type" "C603H36"
			(at 0 -4.3434 0)
			(unlocked yes)
			(layer "F.Fab")
			(hide yes)
			(effects
				(font
					(size 1.016 1.016)
					(thickness 0.1524)
				)
			)
		)
		(duplicate_pad_numbers_are_jumpers no)
		(fp_line
			(start 0.508 0)
			(end -0.508 0)
			(stroke
				(width 0.2032)
				(type default)
			)
			(layer "F.SilkS")
		)
		(fp_rect
			(start -0.5842 1.3335)
			(end 0.5842 -1.3335)
			(stroke
				(width 0)
				(type default)
			)
			(fill no)
			(layer "F.CrtYd")
		)
		(fp_rect
			(start -0.5842 1.3335)
			(end 0.5842 -1.3335)
			(stroke
				(width 0)
				(type default)
			)
			(fill no)
			(layer "F.Fab")
		)
		(pad "1" smd custom
			(at 0 -0.762)
			(size 0.2159 0.2159)
			(layers "F.Cu" "F.Mask" "F.Paste")
			(net "P1V8_E_BIAS")
			(options
				(clearance outline)
				(anchor circle)
			)
			(primitives
				(gr_poly
					(pts
						(arc
							(start -0.3302 -0.4318)
							(mid -0.402042 -0.402042)
							(end -0.4318 -0.3302)
						)
						(arc
							(start -0.4318 0.3302)
							(mid -0.402042 0.402042)
							(end -0.3302 0.4318)
						)
						(arc
							(start 0.3302 0.4318)
							(mid 0.402042 0.402042)
							(end 0.4318 0.3302)
						)
						(arc
							(start 0.4318 -0.3302)
							(mid 0.402042 -0.402042)
							(end 0.3302 -0.4318)
						)
					)
					(width 0)
					(fill yes)
				)
			)
		)
		(pad "2" smd custom
			(at 0 0.762)
			(size 0.2159 0.2159)
			(layers "F.Cu" "F.Mask" "F.Paste")
			(net "GND")
			(options
				(clearance outline)
				(anchor circle)
			)
			(primitives
				(gr_poly
					(pts
						(arc
							(start -0.3302 -0.4318)
							(mid -0.402042 -0.402042)
							(end -0.4318 -0.3302)
						)
						(arc
							(start -0.4318 0.3302)
							(mid -0.402042 0.402042)
							(end -0.3302 0.4318)
						)
						(arc
							(start 0.3302 0.4318)
							(mid 0.402042 0.402042)
							(end 0.4318 0.3302)
						)
						(arc
							(start 0.4318 -0.3302)
							(mid 0.402042 -0.402042)
							(end 0.3302 -0.4318)
						)
					)
					(width 0)
					(fill yes)
				)
			)
		)
	)
	(footprint ""
		(layer "F.Cu")
		(at 69.181472 -96.0628 -90)
		(property "Reference" "R504"
			(at 0 0 270)
			(layer "F.SilkS")
			(hide yes)
			(effects
				(font
					(size 1.27 1.27)
				)
			)
		)
		(property "Value" "51KR2F-L-GP"
			(at 0.064008 -3.993896 270)
			(unlocked yes)
			(layer "F.Fab")
			(hide yes)
			(effects
				(font
					(size 1.016 1.016)
					(thickness 0.1524)
				)
			)
		)
		(property "Device Type" "R402H16"
			(at 0.064008 -5.517896 270)
			(unlocked yes)
			(layer "F.Fab")
			(hide yes)
			(effects
				(font
					(size 1.016 1.016)
					(thickness 0.1524)
				)
			)
		)
		(duplicate_pad_numbers_are_jumpers no)
		(fp_line
			(start -0.508 -0.9398)
			(end -0.508 0.9398)
			(stroke
				(width 0.1524)
				(type default)
			)
			(layer "F.SilkS")
		)
		(fp_line
			(start 0.508 -0.9398)
			(end -0.508 -0.9398)
			(stroke
				(width 0.1524)
				(type default)
			)
			(layer "F.SilkS")
		)
		(fp_rect
			(start -0.508 0.9398)
			(end 0.508 -0.9398)
			(stroke
				(width 0)
				(type default)
			)
			(fill no)
			(layer "F.CrtYd")
		)
		(fp_rect
			(start -0.508 0.9398)
			(end 0.508 -0.9398)
			(stroke
				(width 0)
				(type default)
			)
			(fill no)
			(layer "F.Fab")
		)
		(pad "1" smd custom
			(at 0 -0.4445 270)
			(size 0.1397 0.1397)
			(layers "F.Cu" "F.Mask" "F.Paste")
			(net "AGND_P3V3")
			(options
				(clearance outline)
				(anchor circle)
			)
			(primitives
				(gr_poly
					(pts
						(arc
							(start -0.1778 -0.2794)
							(mid -0.249642 -0.249642)
							(end -0.2794 -0.1778)
						)
						(arc
							(start -0.2794 0.1778)
							(mid -0.249642 0.249642)
							(end -0.1778 0.2794)
						)
						(arc
							(start 0.1778 0.2794)
							(mid 0.249642 0.249642)
							(end 0.2794 0.1778)
						)
						(arc
							(start 0.2794 -0.1778)
							(mid 0.249642 -0.249642)
							(end 0.1778 -0.2794)
						)
					)
					(width 0)
					(fill yes)
				)
			)
		)
		(pad "2" smd custom
			(at 0 0.4445 270)
			(size 0.1397 0.1397)
			(layers "F.Cu" "F.Mask" "F.Paste")
			(net "P3V3_TRIP")
			(options
				(clearance outline)
				(anchor circle)
			)
			(primitives
				(gr_poly
					(pts
						(arc
							(start -0.1778 -0.2794)
							(mid -0.249642 -0.249642)
							(end -0.2794 -0.1778)
						)
						(arc
							(start -0.2794 0.1778)
							(mid -0.249642 0.249642)
							(end -0.1778 0.2794)
						)
						(arc
							(start 0.1778 0.2794)
							(mid 0.249642 0.249642)
							(end 0.2794 0.1778)
						)
						(arc
							(start 0.2794 -0.1778)
							(mid 0.249642 -0.249642)
							(end 0.1778 -0.2794)
						)
					)
					(width 0)
					(fill yes)
				)
			)
		)
	)
	(footprint ""
		(layer "F.Cu")
		(at 61.7982 -91.1098 180)
		(property "Reference" "L28"
			(at 0 0 180)
			(layer "F.SilkS")
			(hide yes)
			(effects
				(font
					(size 1.27 1.27)
				)
			)
		)
		(property "Value" "BLM21PG220SN1DGP"
			(at 0.0254 -5.6896 180)
			(unlocked yes)
			(layer "F.Fab")
			(hide yes)
			(effects
				(font
					(size 1.016 1.016)
					(thickness 0.1524)
				)
			)
		)
		(property "Device Type" "L20125H42"
			(at 0.0254 -7.5946 180)
			(unlocked yes)
			(layer "F.Fab")
			(hide yes)
			(effects
				(font
					(size 1.016 1.016)
					(thickness 0.1524)
				)
			)
		)
		(duplicate_pad_numbers_are_jumpers no)
		(fp_line
			(start 0.9144 1.7018)
			(end 0.9144 -1.7018)
			(stroke
				(width 0.1524)
				(type default)
			)
			(layer "F.SilkS")
		)
		(fp_line
			(start 0.9144 -1.7018)
			(end -0.9144 -1.7018)
			(stroke
				(width 0.1524)
				(type default)
			)
			(layer "F.SilkS")
		)
		(fp_line
			(start -0.9144 1.7018)
			(end 0.9144 1.7018)
			(stroke
				(width 0.1524)
				(type default)
			)
			(layer "F.SilkS")
		)
		(fp_line
			(start -0.9144 -1.7018)
			(end -0.9144 1.7018)
			(stroke
				(width 0.1524)
				(type default)
			)
			(layer "F.SilkS")
		)
		(fp_rect
			(start -1.0033 1.778)
			(end 1.0033 -1.778)
			(stroke
				(width 0)
				(type default)
			)
			(fill no)
			(layer "F.CrtYd")
		)
		(fp_poly
			(pts
				(xy -1.0033 -1.778) (xy 1.0033 -1.778) (xy 1.0033 1.778) (xy -1.0033 1.778)
			)
			(stroke
				(width 0)
				(type default)
			)
			(fill no)
			(layer "F.Fab")
		)
		(pad "1" smd rect
			(at 0 -0.9652 180)
			(size 1.397 1.143)
			(layers "F.Cu" "F.Mask" "F.Paste")
			(net "P12V_STBY_SCC")
		)
		(pad "2" smd rect
			(at 0 0.9652 180)
			(size 1.397 1.143)
			(layers "F.Cu" "F.Mask" "F.Paste")
			(net "P12V_STBY_VIN_U10")
		)
	)
	(footprint ""
		(layer "F.Cu")
		(at 70.612 -57.023 90)
		(property "Reference" "R166"
			(at 0 0 90)
			(layer "F.SilkS")
			(hide yes)
			(effects
				(font
					(size 1.27 1.27)
				)
			)
		)
		(property "Value" "D51R3F-2-GP"
			(at -0.0254 -2.5146 90)
			(unlocked yes)
			(layer "F.Fab")
			(hide yes)
			(effects
				(font
					(size 1.016 1.016)
					(thickness 0.1524)
				)
			)
		)
		(property "Device Type" "R603H22"
			(at -0.0254 -4.0386 90)
			(unlocked yes)
			(layer "F.Fab")
			(hide yes)
			(effects
				(font
					(size 1.016 1.016)
					(thickness 0.1524)
				)
			)
		)
		(duplicate_pad_numbers_are_jumpers no)
		(fp_line
			(start 0.2032 0)
			(end 0.4826 0)
			(stroke
				(width 0.2032)
				(type default)
			)
			(layer "F.SilkS")
		)
		(fp_line
			(start -0.4826 0)
			(end -0.2032 0)
			(stroke
				(width 0.2032)
				(type default)
			)
			(layer "F.SilkS")
		)
		(fp_rect
			(start -0.5842 1.3335)
			(end 0.5842 -1.3335)
			(stroke
				(width 0)
				(type default)
			)
			(fill no)
			(layer "F.CrtYd")
		)
		(fp_rect
			(start -0.5842 1.3335)
			(end 0.5842 -1.3335)
			(stroke
				(width 0)
				(type default)
			)
			(fill no)
			(layer "F.Fab")
		)
		(pad "1" smd custom
			(at 0 -0.762 90)
			(size 0.2159 0.2159)
			(layers "F.Cu" "F.Mask" "F.Paste")
			(net "P0V9")
			(options
				(clearance outline)
				(anchor circle)
			)
			(primitives
				(gr_poly
					(pts
						(arc
							(start -0.3302 -0.4318)
							(mid -0.402042 -0.402042)
							(end -0.4318 -0.3302)
						)
						(arc
							(start -0.4318 0.3302)
							(mid -0.402042 0.402042)
							(end -0.3302 0.4318)
						)
						(arc
							(start 0.3302 0.4318)
							(mid 0.402042 0.402042)
							(end 0.4318 0.3302)
						)
						(arc
							(start 0.4318 -0.3302)
							(mid 0.402042 -0.402042)
							(end 0.3302 -0.4318)
						)
					)
					(width 0)
					(fill yes)
				)
			)
		)
		(pad "2" smd custom
			(at 0 0.762 90)
			(size 0.2159 0.2159)
			(layers "F.Cu" "F.Mask" "F.Paste")
			(net "GB_VDDA")
			(options
				(clearance outline)
				(anchor circle)
			)
			(primitives
				(gr_poly
					(pts
						(arc
							(start -0.3302 -0.4318)
							(mid -0.402042 -0.402042)
							(end -0.4318 -0.3302)
						)
						(arc
							(start -0.4318 0.3302)
							(mid -0.402042 0.402042)
							(end -0.3302 0.4318)
						)
						(arc
							(start 0.3302 0.4318)
							(mid 0.402042 0.402042)
							(end 0.4318 0.3302)
						)
						(arc
							(start 0.4318 -0.3302)
							(mid 0.402042 -0.402042)
							(end 0.3302 -0.4318)
						)
					)
					(width 0)
					(fill yes)
				)
			)
		)
	)
	(footprint ""
		(layer "F.Cu")
		(at 175.70069 -112.063784 90)
		(property "Reference" "C601"
			(at 0 0 90)
			(layer "F.SilkS")
			(hide yes)
			(effects
				(font
					(size 1.27 1.27)
				)
			)
		)
		(property "Value" "SCD1U16V2KX-3GP"
			(at 1.1811 -2.7051 90)
			(unlocked yes)
			(layer "F.Fab")
			(hide yes)
			(effects
				(font
					(size 1.016 1.016)
					(thickness 0.1524)
				)
			)
		)
		(property "Device Type" "C402H22"
			(at 1.1811 -4.2291 90)
			(unlocked yes)
			(layer "F.Fab")
			(hide yes)
			(effects
				(font
					(size 1.016 1.016)
					(thickness 0.1524)
				)
			)
		)
		(duplicate_pad_numbers_are_jumpers no)
		(fp_rect
			(start -0.4318 0.9525)
			(end 0.4318 -0.9525)
			(stroke
				(width 0)
				(type default)
			)
			(fill no)
			(layer "F.CrtYd")
		)
		(fp_rect
			(start -0.4318 0.9525)
			(end 0.4318 -0.9525)
			(stroke
				(width 0)
				(type default)
			)
			(fill no)
			(layer "F.Fab")
		)
		(pad "1" smd custom
			(at 0 -0.4445 90)
			(size 0.1524 0.1524)
			(layers "F.Cu" "F.Mask" "F.Paste")
			(net "P1V8_E_EN")
			(options
				(clearance outline)
				(anchor circle)
			)
			(primitives
				(gr_poly
					(pts
						(arc
							(start 0.3048 -0.2032)
							(mid 0.275042 -0.275042)
							(end 0.2032 -0.3048)
						)
						(arc
							(start -0.2032 -0.3048)
							(mid -0.275042 -0.275042)
							(end -0.3048 -0.2032)
						)
						(arc
							(start -0.3048 0.2032)
							(mid -0.275042 0.275042)
							(end -0.2032 0.3048)
						)
						(arc
							(start 0.2032 0.3048)
							(mid 0.275042 0.275042)
							(end 0.3048 0.2032)
						)
					)
					(width 0)
					(fill yes)
				)
			)
		)
		(pad "2" smd custom
			(at 0 0.4445 90)
			(size 0.1524 0.1524)
			(layers "F.Cu" "F.Mask" "F.Paste")
			(net "GND")
			(options
				(clearance outline)
				(anchor circle)
			)
			(primitives
				(gr_poly
					(pts
						(arc
							(start 0.3048 -0.2032)
							(mid 0.275042 -0.275042)
							(end 0.2032 -0.3048)
						)
						(arc
							(start -0.2032 -0.3048)
							(mid -0.275042 -0.275042)
							(end -0.3048 -0.2032)
						)
						(arc
							(start -0.3048 0.2032)
							(mid -0.275042 0.275042)
							(end -0.2032 0.3048)
						)
						(arc
							(start 0.2032 0.3048)
							(mid 0.275042 0.275042)
							(end 0.3048 0.2032)
						)
					)
					(width 0)
					(fill yes)
				)
			)
		)
	)
	(footprint ""
		(layer "F.Cu")
		(at 178.407314 -23.56104 90)
		(property "Reference" "VIA7"
			(at 0 0 90)
			(layer "F.SilkS")
			(hide yes)
			(effects
				(font
					(size 1.27 1.27)
				)
			)
		)
		(property "Value" "85OHM-8L-1D6MM-L16L18-GP"
			(at 4.064 0.6096 90)
			(unlocked yes)
			(layer "F.Fab")
			(hide yes)
			(effects
				(font
					(size 1.016 1.016)
					(thickness 0.1524)
				)
			)
		)
		(property "Device Type" "VIA-PCIE-4P-368076"
			(at 4.064 -0.9144 90)
			(unlocked yes)
			(layer "F.Fab")
			(hide yes)
			(effects
				(font
					(size 1.016 1.016)
					(thickness 0.1524)
				)
			)
		)
		(duplicate_pad_numbers_are_jumpers no)
		(fp_rect
			(start -1.8415 0.381)
			(end 1.8415 -0.381)
			(stroke
				(width 0)
				(type default)
			)
			(fill no)
			(layer "F.CrtYd")
		)
		(fp_rect
			(start -1.8415 0.381)
			(end 1.8415 -0.381)
			(stroke
				(width 0)
				(type default)
			)
			(fill no)
			(layer "F.Fab")
		)
		(pad "1" thru_hole circle
			(at -1.4605 0 90)
			(size 0.508 0.508)
			(drill 0.254)
			(layers "*.Cu" "*.Mask")
			(remove_unused_layers no)
			(net "GND")
			(clearance 0.127)
			(thermal_gap 0.127)
		)
		(pad "2" thru_hole circle
			(at -0.4445 0 90)
			(size 0.508 0.508)
			(drill 0.254)
			(layers "*.Cu" "*.Mask")
			(remove_unused_layers no)
			(net "PCIE_COMP_TO_SCC_6_DP")
			(clearance 0.127)
			(thermal_gap 0.127)
		)
		(pad "3" thru_hole circle
			(at 0.4445 0 90)
			(size 0.508 0.508)
			(drill 0.254)
			(layers "*.Cu" "*.Mask")
			(remove_unused_layers no)
			(net "PCIE_COMP_TO_SCC_6_DN")
			(clearance 0.127)
			(thermal_gap 0.127)
		)
		(pad "4" thru_hole circle
			(at 1.4605 0 90)
			(size 0.508 0.508)
			(drill 0.254)
			(layers "*.Cu" "*.Mask")
			(remove_unused_layers no)
			(net "GND")
			(clearance 0.127)
			(thermal_gap 0.127)
		)
	)
)
